(kicad_pcb
	(version 20260206)
	(generator "pcbnew")
	(generator_version "10.0")
	(general
		(thickness 1.6)
		(legacy_teardrops no)
	)
	(paper "A4")
	(title_block
		(title "04192023_DAF0TMB3IC0_F0TG_MB_C_brd_V02_OCP.brd")
		(comment 1 "Grand Teton / footprints 995-1000 of 8354")
	)
	(layers
		(0 "F.Cu" signal "TOP")
		(4 "In1.Cu" signal "GND")
		(6 "In2.Cu" signal "IN1")
		(8 "In3.Cu" signal "GND1")
		(10 "In4.Cu" signal "IN2")
		(12 "In5.Cu" signal "GND2")
		(14 "In6.Cu" signal "IN3")
		(16 "In7.Cu" signal "GND3")
		(18 "In8.Cu" signal "VCC")
		(20 "In9.Cu" signal "VCC1")
		(22 "In10.Cu" signal "GND4")
		(24 "In11.Cu" signal "IN4")
		(26 "In12.Cu" signal "GND5")
		(28 "In13.Cu" signal "IN5")
		(30 "In14.Cu" signal "GND6")
		(32 "In15.Cu" signal "IN6")
		(34 "In16.Cu" signal "GND7")
		(2 "B.Cu" signal "BOTTOM")
		(9 "F.Adhes" user "F.Adhesive")
		(11 "B.Adhes" user "B.Adhesive")
		(13 "F.Paste" user "Package Geometry/Pastemask Top")
		(15 "B.Paste" user "Package Geometry/Pastemask Bottom")
		(5 "F.SilkS" user "Ref Des/Silkscreen Top")
		(7 "B.SilkS" user "Ref Des/Silkscreen Bottom")
		(1 "F.Mask" user "Board Geometry/Soldermask Top")
		(3 "B.Mask" user "Board Geometry/Soldermask Bottom")
		(17 "Dwgs.User" user "User.Drawings")
		(19 "Cmts.User" user "User.Comments")
		(21 "Eco1.User" user "User.Eco1")
		(23 "Eco2.User" user "User.Eco2")
		(25 "Edge.Cuts" user "Board Geometry/Outline")
		(27 "Margin" user)
		(31 "F.CrtYd" user "Package Geometry/Place Bound Top")
		(29 "B.CrtYd" user "Package Geometry/Place Bound Bottom")
		(35 "F.Fab" user "Ref Des/Assembly Top")
		(33 "B.Fab" user "Ref Des/Assembly Bottom")
	)
	(footprint ""
		(layer "F.Cu")
		(at 177.419 -404.495 90)
		(property "Reference" "PC2191"
			(at 0 0 90)
			(layer "F.SilkS")
			(hide yes)
			(effects
				(font
					(size 1.27 1.27)
				)
			)
		)
		(property "Value" ""
			(at 0 0 90)
			(layer "F.Fab")
			(effects
				(font
					(size 1.27 1.27)
				)
			)
		)
		(duplicate_pad_numbers_are_jumpers no)
		(fp_line
			(start 0.7874 -0.4064)
			(end 0.7874 0.4064)
			(stroke
				(width 0.1524)
				(type default)
			)
			(layer "F.SilkS")
		)
		(fp_line
			(start -0.7874 -0.4064)
			(end 0.7874 -0.4064)
			(stroke
				(width 0.1524)
				(type default)
			)
			(layer "F.SilkS")
		)
		(fp_line
			(start 0.7874 0.4064)
			(end -0.7874 0.4064)
			(stroke
				(width 0.1524)
				(type default)
			)
			(layer "F.SilkS")
		)
		(fp_line
			(start -0.7874 0.4064)
			(end -0.7874 -0.4064)
			(stroke
				(width 0.1524)
				(type default)
			)
			(layer "F.SilkS")
		)
		(fp_line
			(start -0.12065 -0.305054)
			(end -0.12065 -0.2794)
			(stroke
				(width 0.1)
				(type default)
			)
			(layer "F.Fab")
		)
		(fp_line
			(start -0.67945 -0.305054)
			(end -0.12065 -0.305054)
			(stroke
				(width 0.1)
				(type default)
			)
			(layer "F.Fab")
		)
		(fp_line
			(start 0.67945 -0.3048)
			(end 0.67945 0.3048)
			(stroke
				(width 0.1)
				(type default)
			)
			(layer "F.Fab")
		)
		(fp_line
			(start 0.12065 -0.3048)
			(end 0.67945 -0.3048)
			(stroke
				(width 0.1)
				(type default)
			)
			(layer "F.Fab")
		)
		(fp_line
			(start 0.12065 -0.2794)
			(end 0.12065 -0.3048)
			(stroke
				(width 0.1)
				(type default)
			)
			(layer "F.Fab")
		)
		(fp_line
			(start -0.12065 -0.2794)
			(end 0.12065 -0.2794)
			(stroke
				(width 0.1)
				(type default)
			)
			(layer "F.Fab")
		)
		(fp_line
			(start 0.120396 0.2794)
			(end -0.12065 0.2794)
			(stroke
				(width 0.1)
				(type default)
			)
			(layer "F.Fab")
		)
		(fp_line
			(start -0.12065 0.2794)
			(end -0.12065 0.3048)
			(stroke
				(width 0.1)
				(type default)
			)
			(layer "F.Fab")
		)
		(fp_line
			(start 0.67945 0.3048)
			(end 0.120396 0.3048)
			(stroke
				(width 0.1)
				(type default)
			)
			(layer "F.Fab")
		)
		(fp_line
			(start 0.120396 0.3048)
			(end 0.120396 0.2794)
			(stroke
				(width 0.1)
				(type default)
			)
			(layer "F.Fab")
		)
		(fp_line
			(start -0.12065 0.3048)
			(end -0.67945 0.3048)
			(stroke
				(width 0.1)
				(type default)
			)
			(layer "F.Fab")
		)
		(fp_line
			(start -0.67945 0.3048)
			(end -0.67945 -0.305054)
			(stroke
				(width 0.1)
				(type default)
			)
			(layer "F.Fab")
		)
		(pad "1" smd circle
			(at -0.40005 0 90)
			(size 0 0)
			(layers "F.Cu" "F.Mask" "F.Paste")
			(net "HSC_SS")
		)
		(pad "2" smd circle
			(at 0.40005 0 90)
			(size 0 0)
			(layers "F.Cu" "F.Mask" "F.Paste")
			(net "AGND_HSC")
		)
	)
	(footprint ""
		(layer "F.Cu")
		(at 111.13897 -178.173634 90)
		(property "Reference" "PC289_C0P1_4"
			(at 0 0 90)
			(layer "F.SilkS")
			(hide yes)
			(effects
				(font
					(size 1.27 1.27)
				)
			)
		)
		(property "Value" ""
			(at 0 0 90)
			(layer "F.Fab")
			(effects
				(font
					(size 1.27 1.27)
				)
			)
		)
		(duplicate_pad_numbers_are_jumpers no)
		(fp_line
			(start 0.7874 -0.4064)
			(end 0.7874 0.4064)
			(stroke
				(width 0.1524)
				(type default)
			)
			(layer "F.SilkS")
		)
		(fp_line
			(start -0.7874 -0.4064)
			(end 0.7874 -0.4064)
			(stroke
				(width 0.1524)
				(type default)
			)
			(layer "F.SilkS")
		)
		(fp_line
			(start 0.7874 0.4064)
			(end -0.7874 0.4064)
			(stroke
				(width 0.1524)
				(type default)
			)
			(layer "F.SilkS")
		)
		(fp_line
			(start -0.7874 0.4064)
			(end -0.7874 -0.4064)
			(stroke
				(width 0.1524)
				(type default)
			)
			(layer "F.SilkS")
		)
		(fp_line
			(start -0.12065 -0.305054)
			(end -0.12065 -0.2794)
			(stroke
				(width 0.1)
				(type default)
			)
			(layer "F.Fab")
		)
		(fp_line
			(start -0.67945 -0.305054)
			(end -0.12065 -0.305054)
			(stroke
				(width 0.1)
				(type default)
			)
			(layer "F.Fab")
		)
		(fp_line
			(start 0.67945 -0.3048)
			(end 0.67945 0.3048)
			(stroke
				(width 0.1)
				(type default)
			)
			(layer "F.Fab")
		)
		(fp_line
			(start 0.12065 -0.3048)
			(end 0.67945 -0.3048)
			(stroke
				(width 0.1)
				(type default)
			)
			(layer "F.Fab")
		)
		(fp_line
			(start 0.12065 -0.2794)
			(end 0.12065 -0.3048)
			(stroke
				(width 0.1)
				(type default)
			)
			(layer "F.Fab")
		)
		(fp_line
			(start -0.12065 -0.2794)
			(end 0.12065 -0.2794)
			(stroke
				(width 0.1)
				(type default)
			)
			(layer "F.Fab")
		)
		(fp_line
			(start 0.120396 0.2794)
			(end -0.12065 0.2794)
			(stroke
				(width 0.1)
				(type default)
			)
			(layer "F.Fab")
		)
		(fp_line
			(start -0.12065 0.2794)
			(end -0.12065 0.3048)
			(stroke
				(width 0.1)
				(type default)
			)
			(layer "F.Fab")
		)
		(fp_line
			(start 0.67945 0.3048)
			(end 0.120396 0.3048)
			(stroke
				(width 0.1)
				(type default)
			)
			(layer "F.Fab")
		)
		(fp_line
			(start 0.120396 0.3048)
			(end 0.120396 0.2794)
			(stroke
				(width 0.1)
				(type default)
			)
			(layer "F.Fab")
		)
		(fp_line
			(start -0.12065 0.3048)
			(end -0.67945 0.3048)
			(stroke
				(width 0.1)
				(type default)
			)
			(layer "F.Fab")
		)
		(fp_line
			(start -0.67945 0.3048)
			(end -0.67945 -0.305054)
			(stroke
				(width 0.1)
				(type default)
			)
			(layer "F.Fab")
		)
		(pad "1" smd circle
			(at -0.40005 0 90)
			(size 0 0)
			(layers "F.Cu" "F.Mask" "F.Paste")
			(net "PVDDCR_CPU0_P1_PVCC")
		)
		(pad "2" smd circle
			(at 0.40005 0 90)
			(size 0 0)
			(layers "F.Cu" "F.Mask" "F.Paste")
			(net "GND")
		)
	)
	(footprint ""
		(layer "F.Cu")
		(at 428.283116 -109.26699 90)
		(property "Reference" "PR3791"
			(at 0 0 90)
			(layer "F.SilkS")
			(hide yes)
			(effects
				(font
					(size 1.27 1.27)
				)
			)
		)
		(property "Value" ""
			(at 0 0 90)
			(layer "F.Fab")
			(effects
				(font
					(size 1.27 1.27)
				)
			)
		)
		(duplicate_pad_numbers_are_jumpers no)
		(fp_line
			(start 0.7874 -0.4064)
			(end 0.7874 0.4064)
			(stroke
				(width 0.1524)
				(type default)
			)
			(layer "F.SilkS")
		)
		(fp_line
			(start -0.7874 -0.4064)
			(end 0.7874 -0.4064)
			(stroke
				(width 0.1524)
				(type default)
			)
			(layer "F.SilkS")
		)
		(fp_line
			(start 0.7874 0.4064)
			(end -0.7874 0.4064)
			(stroke
				(width 0.1524)
				(type default)
			)
			(layer "F.SilkS")
		)
		(fp_line
			(start -0.7874 0.4064)
			(end -0.7874 -0.4064)
			(stroke
				(width 0.1524)
				(type default)
			)
			(layer "F.SilkS")
		)
		(fp_line
			(start -0.12065 -0.305054)
			(end -0.12065 -0.2794)
			(stroke
				(width 0.1)
				(type default)
			)
			(layer "F.Fab")
		)
		(fp_line
			(start -0.67945 -0.305054)
			(end -0.12065 -0.305054)
			(stroke
				(width 0.1)
				(type default)
			)
			(layer "F.Fab")
		)
		(fp_line
			(start 0.67945 -0.3048)
			(end 0.67945 0.3048)
			(stroke
				(width 0.1)
				(type default)
			)
			(layer "F.Fab")
		)
		(fp_line
			(start 0.12065 -0.3048)
			(end 0.67945 -0.3048)
			(stroke
				(width 0.1)
				(type default)
			)
			(layer "F.Fab")
		)
		(fp_line
			(start 0.12065 -0.2794)
			(end 0.12065 -0.3048)
			(stroke
				(width 0.1)
				(type default)
			)
			(layer "F.Fab")
		)
		(fp_line
			(start -0.12065 -0.2794)
			(end 0.12065 -0.2794)
			(stroke
				(width 0.1)
				(type default)
			)
			(layer "F.Fab")
		)
		(fp_line
			(start 0.120396 0.2794)
			(end -0.12065 0.2794)
			(stroke
				(width 0.1)
				(type default)
			)
			(layer "F.Fab")
		)
		(fp_line
			(start -0.12065 0.2794)
			(end -0.12065 0.3048)
			(stroke
				(width 0.1)
				(type default)
			)
			(layer "F.Fab")
		)
		(fp_line
			(start 0.67945 0.3048)
			(end 0.120396 0.3048)
			(stroke
				(width 0.1)
				(type default)
			)
			(layer "F.Fab")
		)
		(fp_line
			(start 0.120396 0.3048)
			(end 0.120396 0.2794)
			(stroke
				(width 0.1)
				(type default)
			)
			(layer "F.Fab")
		)
		(fp_line
			(start -0.12065 0.3048)
			(end -0.67945 0.3048)
			(stroke
				(width 0.1)
				(type default)
			)
			(layer "F.Fab")
		)
		(fp_line
			(start -0.67945 0.3048)
			(end -0.67945 -0.305054)
			(stroke
				(width 0.1)
				(type default)
			)
			(layer "F.Fab")
		)
		(pad "1" smd circle
			(at -0.40005 0 90)
			(size 0 0)
			(layers "F.Cu" "F.Mask" "F.Paste")
			(net "P3V3_OCP_OV_1")
		)
		(pad "2" smd circle
			(at 0.40005 0 90)
			(size 0 0)
			(layers "F.Cu" "F.Mask" "F.Paste")
			(net "GND")
		)
	)
	(footprint ""
		(layer "F.Cu")
		(at 360.40949 -393.9032 90)
		(property "Reference" "R1013"
			(at 0 0 90)
			(layer "F.SilkS")
			(hide yes)
			(effects
				(font
					(size 1.27 1.27)
				)
			)
		)
		(property "Value" ""
			(at 0 0 90)
			(layer "F.Fab")
			(effects
				(font
					(size 1.27 1.27)
				)
			)
		)
		(duplicate_pad_numbers_are_jumpers no)
		(fp_line
			(start 0.32512 -0.175006)
			(end 0.32512 0.175006)
			(stroke
				(width 0.1)
				(type default)
			)
			(layer "F.Fab")
		)
		(fp_line
			(start -0.32512 -0.175006)
			(end 0.32512 -0.175006)
			(stroke
				(width 0.1)
				(type default)
			)
			(layer "F.Fab")
		)
		(fp_line
			(start 0.32512 0.175006)
			(end -0.32512 0.175006)
			(stroke
				(width 0.1)
				(type default)
			)
			(layer "F.Fab")
		)
		(fp_line
			(start -0.32512 0.175006)
			(end -0.32512 -0.175006)
			(stroke
				(width 0.1)
				(type default)
			)
			(layer "F.Fab")
		)
		(pad "1" smd rect
			(at -0.2667 0 90)
			(size 0.3048 0.381)
			(layers "F.Cu" "F.Mask" "F.Paste")
			(net "P1V8_CPU0_RT_1D")
		)
		(pad "2" smd rect
			(at 0.2667 0 270)
			(size 0.3048 0.381)
			(layers "F.Cu" "F.Mask" "F.Paste")
			(net "RT_CPU0_P1_ADDR3")
		)
	)
	(footprint ""
		(layer "F.Cu")
		(at 192.599564 -68.407788 180)
		(property "Reference" "PC2197"
			(at 0 0 180)
			(layer "F.SilkS")
			(hide yes)
			(effects
				(font
					(size 1.27 1.27)
				)
			)
		)
		(property "Value" ""
			(at 0 0 180)
			(layer "F.Fab")
			(effects
				(font
					(size 1.27 1.27)
				)
			)
		)
		(duplicate_pad_numbers_are_jumpers no)
		(fp_line
			(start 0.7874 0.4064)
			(end -0.7874 0.4064)
			(stroke
				(width 0.1524)
				(type default)
			)
			(layer "F.SilkS")
		)
		(fp_line
			(start 0.7874 -0.4064)
			(end 0.7874 0.4064)
			(stroke
				(width 0.1524)
				(type default)
			)
			(layer "F.SilkS")
		)
		(fp_line
			(start -0.7874 0.4064)
			(end -0.7874 -0.4064)
			(stroke
				(width 0.1524)
				(type default)
			)
			(layer "F.SilkS")
		)
		(fp_line
			(start -0.7874 -0.4064)
			(end 0.7874 -0.4064)
			(stroke
				(width 0.1524)
				(type default)
			)
			(layer "F.SilkS")
		)
		(fp_line
			(start 0.67945 0.3048)
			(end 0.120396 0.3048)
			(stroke
				(width 0.1)
				(type default)
			)
			(layer "F.Fab")
		)
		(fp_line
			(start 0.67945 -0.3048)
			(end 0.67945 0.3048)
			(stroke
				(width 0.1)
				(type default)
			)
			(layer "F.Fab")
		)
		(fp_line
			(start 0.12065 -0.2794)
			(end 0.12065 -0.3048)
			(stroke
				(width 0.1)
				(type default)
			)
			(layer "F.Fab")
		)
		(fp_line
			(start 0.12065 -0.3048)
			(end 0.67945 -0.3048)
			(stroke
				(width 0.1)
				(type default)
			)
			(layer "F.Fab")
		)
		(fp_line
			(start 0.120396 0.3048)
			(end 0.120396 0.2794)
			(stroke
				(width 0.1)
				(type default)
			)
			(layer "F.Fab")
		)
		(fp_line
			(start 0.120396 0.2794)
			(end -0.12065 0.2794)
			(stroke
				(width 0.1)
				(type default)
			)
			(layer "F.Fab")
		)
		(fp_line
			(start -0.12065 0.3048)
			(end -0.67945 0.3048)
			(stroke
				(width 0.1)
				(type default)
			)
			(layer "F.Fab")
		)
		(fp_line
			(start -0.12065 0.2794)
			(end -0.12065 0.3048)
			(stroke
				(width 0.1)
				(type default)
			)
			(layer "F.Fab")
		)
		(fp_line
			(start -0.12065 -0.2794)
			(end 0.12065 -0.2794)
			(stroke
				(width 0.1)
				(type default)
			)
			(layer "F.Fab")
		)
		(fp_line
			(start -0.12065 -0.305054)
			(end -0.12065 -0.2794)
			(stroke
				(width 0.1)
				(type default)
			)
			(layer "F.Fab")
		)
		(fp_line
			(start -0.67945 0.3048)
			(end -0.67945 -0.305054)
			(stroke
				(width 0.1)
				(type default)
			)
			(layer "F.Fab")
		)
		(fp_line
			(start -0.67945 -0.305054)
			(end -0.12065 -0.305054)
			(stroke
				(width 0.1)
				(type default)
			)
			(layer "F.Fab")
		)
		(pad "1" smd circle
			(at -0.40005 0 180)
			(size 0 0)
			(layers "F.Cu" "F.Mask" "F.Paste")
			(net "P3V3_E1S_MODE_0")
		)
		(pad "2" smd circle
			(at 0.40005 0 180)
			(size 0 0)
			(layers "F.Cu" "F.Mask" "F.Paste")
			(net "GND")
		)
	)
	(footprint ""
		(layer "F.Cu")
		(at 482.294946 -457.301092 90)
		(property "Reference" "X9004"
			(at -2.091182 1.02362 0)
			(unlocked yes)
			(layer "F.SilkS")
			(effects
				(font
					(size 0.7874 0.5842)
					(thickness 0.1524)
				)
				(justify left)
			)
		)
		(property "Value" ""
			(at 0 0 90)
			(layer "F.Fab")
			(effects
				(font
					(size 1.27 1.27)
				)
			)
		)
		(property "User Part Number" "N_A"
			(at 1.30175 1.27 180)
			(unlocked yes)
			(layer "Cmts.User")
			(hide yes)
			(effects
				(font
					(size 0.635 0.4064)
					(thickness 0.1524)
				)
			)
		)
		(property "Device Type" "TP_TDR_4P_FTS_TH-TP_TDR_4P_DIP,EMPTY,TP15"
			(at 1.30175 1.27 180)
			(unlocked yes)
			(layer "F.Fab")
			(hide yes)
			(effects
				(font
					(size 0.635 0.4064)
					(thickness 0.1524)
				)
			)
		)
		(duplicate_pad_numbers_are_jumpers no)
		(fp_line
			(start 2.54 -1.27)
			(end 0 -1.27)
			(stroke
				(width 0.1524)
				(type default)
			)
			(layer "F.SilkS")
		)
		(fp_line
			(start 0 -1.27)
			(end 0 -0.635)
			(stroke
				(width 0.1524)
				(type default)
			)
			(layer "F.SilkS")
		)
		(fp_line
			(start 2.54 -1.1303)
			(end 2.54 -1.27)
			(stroke
				(width 0.1524)
				(type default)
			)
			(layer "F.SilkS")
		)
		(fp_line
			(start 0 0.635)
			(end 0 1.905)
			(stroke
				(width 0.1524)
				(type default)
			)
			(layer "F.SilkS")
		)
		(fp_line
			(start 2.54 1.4097)
			(end 2.54 1.1303)
			(stroke
				(width 0.1524)
				(type default)
			)
			(layer "F.SilkS")
		)
		(fp_line
			(start 0 3.175)
			(end 0 3.81)
			(stroke
				(width 0.1524)
				(type default)
			)
			(layer "F.SilkS")
		)
		(fp_line
			(start 2.54 3.81)
			(end 2.54 3.6703)
			(stroke
				(width 0.1524)
				(type default)
			)
			(layer "F.SilkS")
		)
		(fp_line
			(start 0 3.81)
			(end 2.54 3.81)
			(stroke
				(width 0.1524)
				(type default)
			)
			(layer "F.SilkS")
		)
		(fp_poly
			(pts
				(xy -2.285746 -0.762) (xy -0.761746 0) (xy -2.285746 0.762)
			)
			(stroke
				(width 0)
				(type default)
			)
			(fill yes)
			(layer "F.SilkS")
		)
		(fp_line
			(start 2.54 -1.27)
			(end 0 -1.27)
			(stroke
				(width 0.1)
				(type default)
			)
			(layer "F.Fab")
		)
		(fp_line
			(start 0 -1.27)
			(end 0 3.81)
			(stroke
				(width 0.1)
				(type default)
			)
			(layer "F.Fab")
		)
		(fp_line
			(start 2.54 3.81)
			(end 2.54 -1.27)
			(stroke
				(width 0.1)
				(type default)
			)
			(layer "F.Fab")
		)
		(fp_line
			(start 0 3.81)
			(end 2.54 3.81)
			(stroke
				(width 0.1)
				(type default)
			)
			(layer "F.Fab")
		)
		(fp_poly
			(pts
				(xy -0.761746 0) (xy -2.285746 -0.762) (xy -2.285746 0.762)
			)
			(stroke
				(width 0)
				(type default)
			)
			(fill yes)
			(layer "F.Fab")
		)
		(pad "1" thru_hole circle
			(at 0 0 90)
			(size 1.0033 1.0033)
			(drill 0.249936)
			(layers "*.Cu" "*.Mask")
			(remove_unused_layers no)
			(net "TDR_DIFF_85_NECK_IN3_DP")
			(clearance 0.10795)
			(thermal_gap 0.10795)
			(padstack
				(mode front_inner_back)
				(layer "Inner"
					(shape circle)
					(size 0.8001 0.8001)
					(clearance 0.1524)
				)
				(layer "B.Cu"
					(shape circle)
					(size 1.0033 1.0033)
					(clearance 0.10795)
				)
			)
		)
		(pad "2" thru_hole circle
			(at 2.54 0 90)
			(size 1.9939 1.9939)
			(drill 0.249936)
			(layers "*.Cu" "*.Mask")
			(remove_unused_layers no)
			(net "T1_GND")
			(clearance 0.10795)
			(thermal_gap 0.10795)
			(padstack
				(mode front_inner_back)
				(layer "Inner"
					(shape circle)
					(size 0.8001 0.8001)
					(clearance 0.1524)
				)
				(layer "B.Cu"
					(shape circle)
					(size 1.9939 1.9939)
					(clearance 0.10795)
				)
			)
		)
		(pad "3" thru_hole circle
			(at 2.54 2.54 90)
			(size 1.9939 1.9939)
			(drill 0.249936)
			(layers "*.Cu" "*.Mask")
			(remove_unused_layers no)
			(net "T1_GND")
			(clearance 0.10795)
			(thermal_gap 0.10795)
			(padstack
				(mode front_inner_back)
				(layer "Inner"
					(shape circle)
					(size 0.8001 0.8001)
					(clearance 0.1524)
				)
				(layer "B.Cu"
					(shape circle)
					(size 1.9939 1.9939)
					(clearance 0.10795)
				)
			)
		)
		(pad "4" thru_hole circle
			(at 0 2.54 90)
			(size 1.0033 1.0033)
			(drill 0.249936)
			(layers "*.Cu" "*.Mask")
			(remove_unused_layers no)
			(net "TDR_DIFF_85_NECK_IN3_DN")
			(clearance 0.10795)
			(thermal_gap 0.10795)
			(padstack
				(mode front_inner_back)
				(layer "Inner"
					(shape circle)
					(size 0.8001 0.8001)
					(clearance 0.1524)
				)
				(layer "B.Cu"
					(shape circle)
					(size 1.0033 1.0033)
					(clearance 0.10795)
				)
			)
		)
	)
)
